(kicad_pcb
	(version 20241229)
	(generator "pcbnew")
	(generator_version "9.0")
	(general
		(thickness 1.62)
		(legacy_teardrops no)
	)
	(paper "A3")
	(title_block
		(title "COM Express 7 Baseboard")
		(date "2025-02-04")
		(rev "1.1.2")
		(company "Antmicro Ltd")
		(comment 1 "www.antmicro.com")
		(comment 9 "footprint 489 of 802 (J12), pads 165-204 of 450")
	)
	(layers
		(0 "F.Cu" signal)
		(4 "In1.Cu" signal)
		(6 "In2.Cu" signal)
		(8 "In3.Cu" signal)
		(10 "In4.Cu" signal)
		(12 "In5.Cu" signal)
		(14 "In6.Cu" signal)
		(2 "B.Cu" signal)
		(9 "F.Adhes" user "F.Adhesive")
		(11 "B.Adhes" user "B.Adhesive")
		(13 "F.Paste" user)
		(15 "B.Paste" user)
		(5 "F.SilkS" user "F.Silkscreen")
		(7 "B.SilkS" user "B.Silkscreen")
		(1 "F.Mask" user)
		(3 "B.Mask" user)
		(17 "Dwgs.User" user "User.Drawings")
		(19 "Cmts.User" user "User.Comments")
		(21 "Eco1.User" user "User.Eco1")
		(23 "Eco2.User" user "User.Eco2")
		(25 "Edge.Cuts" user)
		(27 "Margin" user)
		(31 "F.CrtYd" user "F.Courtyard")
		(29 "B.CrtYd" user "B.Courtyard")
		(35 "F.Fab" user)
		(33 "B.Fab" user)
	)
	(footprint "antmicro-footprints:EPT_401-51501-51"
		(layer "F.Cu")
		(at 203.275 159.81)
		(property "Reference" "J12"
			(at 30.975 -10.45 0)
			(layer "F.SilkS")
			(effects
				(font
					(size 0.7 0.7)
					(thickness 0.15)
				)
				(justify right top)
			)
		)
		(property "Value" "Plug_Bus_CE7_EPT_401-51501-51"
			(at -3.225 52.665 0)
			(layer "F.Fab")
			(hide yes)
			(effects
				(font
					(size 0.7 0.7)
					(thickness 0.15)
				)
				(justify left top)
			)
		)
		(property "Datasheet" "https://www.farnell.com/datasheets/1905093.pdf"
			(at 0 0 0)
			(layer "F.Fab")
			(hide yes)
			(effects
				(font
					(size 1.27 1.27)
					(thickness 0.15)
				)
			)
		)
		(property "Author" "Antmicro"
			(at 406.55 319.62 0)
			(layer "F.Fab")
			(hide yes)
			(effects
				(font
					(size 1 1)
					(thickness 0.15)
				)
			)
		)
		(property "License" "Apache-2.0"
			(at 406.55 319.62 0)
			(layer "F.Fab")
			(hide yes)
			(effects
				(font
					(size 1 1)
					(thickness 0.15)
				)
			)
		)
		(property "MPN" "401-51501-51"
			(at 406.55 319.62 0)
			(layer "F.Fab")
			(hide yes)
			(effects
				(font
					(size 1 1)
					(thickness 0.15)
				)
			)
		)
		(property "Manufacturer" "ept"
			(at 406.55 319.62 0)
			(layer "F.Fab")
			(hide yes)
			(effects
				(font
					(size 1 1)
					(thickness 0.15)
				)
			)
		)
		(sheetname "Com Express 7 Interfaces")
		(sheetfile "com_express_7_interfaces.kicad_sch")
		(attr smd)
		(pad "B50" smd rect
			(at -2.75 3.325)
			(size 0.3 1.75)
			(layers "F.Cu" "F.Mask" "F.Paste")
			(net 382 "Net-(J12D-~{CB_RESET})")
			(pinfunction "~{CB_RESET}")
			(pintype "output")
			(teardrops
				(best_length_ratio 0.2)
				(max_length 1)
				(best_width_ratio 0.9)
				(max_width 2)
				(curved_edges yes)
				(filter_ratio 0.9)
				(enabled yes)
				(allow_two_segments yes)
				(prefer_zone_connections yes)
			)
		)
		(pad "B51" smd rect
			(at -2.25 3.325)
			(size 0.3 1.75)
			(layers "F.Cu" "F.Mask" "F.Paste")
			(net 1 "GND")
			(pinfunction "GND(FIXED)")
			(pintype "passive")
			(teardrops
				(best_length_ratio 0.2)
				(max_length 1)
				(best_width_ratio 0.9)
				(max_width 2)
				(curved_edges yes)
				(filter_ratio 0.9)
				(enabled yes)
				(allow_two_segments yes)
				(prefer_zone_connections yes)
			)
		)
		(pad "B52" smd rect
			(at -1.75 3.325)
			(size 0.3 1.75)
			(layers "F.Cu" "F.Mask" "F.Paste")
			(net 383 "/Com Express 7 Interfaces/PCIe_{B1x2}.RX1+")
			(pinfunction "PCIE_RX5+")
			(pintype "input+no_connect")
			(teardrops
				(best_length_ratio 0.2)
				(max_length 1)
				(best_width_ratio 0.9)
				(max_width 2)
				(curved_edges yes)
				(filter_ratio 0.9)
				(enabled yes)
				(allow_two_segments yes)
				(prefer_zone_connections yes)
			)
		)
		(pad "B53" smd rect
			(at -1.25 3.325)
			(size 0.3 1.75)
			(layers "F.Cu" "F.Mask" "F.Paste")
			(net 384 "/Com Express 7 Interfaces/PCIe_{B1x2}.RX1-")
			(pinfunction "PCIE_RX5-")
			(pintype "input+no_connect")
			(teardrops
				(best_length_ratio 0.2)
				(max_length 1)
				(best_width_ratio 0.9)
				(max_width 2)
				(curved_edges yes)
				(filter_ratio 0.9)
				(enabled yes)
				(allow_two_segments yes)
				(prefer_zone_connections yes)
			)
		)
		(pad "B54" smd rect
			(at -0.75 3.325)
			(size 0.3 1.75)
			(layers "F.Cu" "F.Mask" "F.Paste")
			(net 385 "/Com Express 7 Interfaces/SDIO.CMD")
			(pinfunction "GPO1")
			(pintype "output")
			(teardrops
				(best_length_ratio 0.2)
				(max_length 1)
				(best_width_ratio 0.9)
				(max_width 2)
				(curved_edges yes)
				(filter_ratio 0.9)
				(enabled yes)
				(allow_two_segments yes)
				(prefer_zone_connections yes)
			)
		)
		(pad "B55" smd rect
			(at -0.25 3.325)
			(size 0.3 1.75)
			(layers "F.Cu" "F.Mask" "F.Paste")
			(net 14 "/Com Express 7 Interfaces/PCIe_{B1x2}.RX0+")
			(pinfunction "PCIE_RX4+")
			(pintype "input")
			(teardrops
				(best_length_ratio 0.2)
				(max_length 1)
				(best_width_ratio 0.9)
				(max_width 2)
				(curved_edges yes)
				(filter_ratio 0.9)
				(enabled yes)
				(allow_two_segments yes)
				(prefer_zone_connections yes)
			)
		)
		(pad "B56" smd rect
			(at 0.25 3.325)
			(size 0.3 1.75)
			(layers "F.Cu" "F.Mask" "F.Paste")
			(net 16 "/Com Express 7 Interfaces/PCIe_{B1x2}.RX0-")
			(pinfunction "PCIE_RX4-")
			(pintype "input")
			(teardrops
				(best_length_ratio 0.2)
				(max_length 1)
				(best_width_ratio 0.9)
				(max_width 2)
				(curved_edges yes)
				(filter_ratio 0.9)
				(enabled yes)
				(allow_two_segments yes)
				(prefer_zone_connections yes)
			)
		)
		(pad "B57" smd rect
			(at 0.75 3.325)
			(size 0.3 1.75)
			(layers "F.Cu" "F.Mask" "F.Paste")
			(net 386 "/Com Express 7 Interfaces/SD_WP")
			(pinfunction "GPO2")
			(pintype "output")
			(teardrops
				(best_length_ratio 0.2)
				(max_length 1)
				(best_width_ratio 0.9)
				(max_width 2)
				(curved_edges yes)
				(filter_ratio 0.9)
				(enabled yes)
				(allow_two_segments yes)
				(prefer_zone_connections yes)
			)
		)
		(pad "B58" smd rect
			(at 1.25 3.325)
			(size 0.3 1.75)
			(layers "F.Cu" "F.Mask" "F.Paste")
			(net 210 "/Com Express 7 Interfaces/PCIe_{B1x4}.RX3+")
			(pinfunction "PCIE_RX3+")
			(pintype "input")
			(teardrops
				(best_length_ratio 0.2)
				(max_length 1)
				(best_width_ratio 0.9)
				(max_width 2)
				(curved_edges yes)
				(filter_ratio 0.9)
				(enabled yes)
				(allow_two_segments yes)
				(prefer_zone_connections yes)
			)
		)
		(pad "B59" smd rect
			(at 1.75 3.325)
			(size 0.3 1.75)
			(layers "F.Cu" "F.Mask" "F.Paste")
			(net 209 "/Com Express 7 Interfaces/PCIe_{B1x4}.RX3-")
			(pinfunction "PCIE_RX3-")
			(pintype "input")
			(teardrops
				(best_length_ratio 0.2)
				(max_length 1)
				(best_width_ratio 0.9)
				(max_width 2)
				(curved_edges yes)
				(filter_ratio 0.9)
				(enabled yes)
				(allow_two_segments yes)
				(prefer_zone_connections yes)
			)
		)
		(pad "B60" smd rect
			(at 2.25 3.325)
			(size 0.3 1.75)
			(layers "F.Cu" "F.Mask" "F.Paste")
			(net 1 "GND")
			(pinfunction "GND(FIXED)")
			(pintype "passive")
			(teardrops
				(best_length_ratio 0.2)
				(max_length 1)
				(best_width_ratio 0.9)
				(max_width 2)
				(curved_edges yes)
				(filter_ratio 0.9)
				(enabled yes)
				(allow_two_segments yes)
				(prefer_zone_connections yes)
			)
		)
		(pad "B61" smd rect
			(at 2.75 3.325)
			(size 0.3 1.75)
			(layers "F.Cu" "F.Mask" "F.Paste")
			(net 214 "/Com Express 7 Interfaces/PCIe_{B1x4}.RX2+")
			(pinfunction "PCIE_RX2+")
			(pintype "input")
			(teardrops
				(best_length_ratio 0.2)
				(max_length 1)
				(best_width_ratio 0.9)
				(max_width 2)
				(curved_edges yes)
				(filter_ratio 0.9)
				(enabled yes)
				(allow_two_segments yes)
				(prefer_zone_connections yes)
			)
		)
		(pad "B62" smd rect
			(at 3.25 3.325)
			(size 0.3 1.75)
			(layers "F.Cu" "F.Mask" "F.Paste")
			(net 213 "/Com Express 7 Interfaces/PCIe_{B1x4}.RX2-")
			(pinfunction "PCIE_RX2-")
			(pintype "input")
			(teardrops
				(best_length_ratio 0.2)
				(max_length 1)
				(best_width_ratio 0.9)
				(max_width 2)
				(curved_edges yes)
				(filter_ratio 0.9)
				(enabled yes)
				(allow_two_segments yes)
				(prefer_zone_connections yes)
			)
		)
		(pad "B63" smd rect
			(at 3.75 3.325)
			(size 0.3 1.75)
			(layers "F.Cu" "F.Mask" "F.Paste")
			(net 531 "/Com Express 7 Interfaces/SD_CD")
			(pinfunction "GPO3")
			(pintype "output")
			(teardrops
				(best_length_ratio 0.2)
				(max_length 1)
				(best_width_ratio 0.9)
				(max_width 2)
				(curved_edges yes)
				(filter_ratio 0.9)
				(enabled yes)
				(allow_two_segments yes)
				(prefer_zone_connections yes)
			)
		)
		(pad "B64" smd rect
			(at 4.25 3.325)
			(size 0.3 1.75)
			(layers "F.Cu" "F.Mask" "F.Paste")
			(net 218 "/Com Express 7 Interfaces/PCIe_{B1x4}.RX1+")
			(pinfunction "PCIE_RX1+")
			(pintype "input")
			(teardrops
				(best_length_ratio 0.2)
				(max_length 1)
				(best_width_ratio 0.9)
				(max_width 2)
				(curved_edges yes)
				(filter_ratio 0.9)
				(enabled yes)
				(allow_two_segments yes)
				(prefer_zone_connections yes)
			)
		)
		(pad "B65" smd rect
			(at 4.75 3.325)
			(size 0.3 1.75)
			(layers "F.Cu" "F.Mask" "F.Paste")
			(net 217 "/Com Express 7 Interfaces/PCIe_{B1x4}.RX1-")
			(pinfunction "PCIE_RX1-")
			(pintype "input")
			(teardrops
				(best_length_ratio 0.2)
				(max_length 1)
				(best_width_ratio 0.9)
				(max_width 2)
				(curved_edges yes)
				(filter_ratio 0.9)
				(enabled yes)
				(allow_two_segments yes)
				(prefer_zone_connections yes)
			)
		)
		(pad "B66" smd rect
			(at 5.25 3.325)
			(size 0.3 1.75)
			(layers "F.Cu" "F.Mask" "F.Paste")
			(net 387 "unconnected-(J12D-~{WAKE0}-PadB66)")
			(pinfunction "~{WAKE0}")
			(pintype "input+no_connect")
			(teardrops
				(best_length_ratio 0.2)
				(max_length 1)
				(best_width_ratio 0.9)
				(max_width 2)
				(curved_edges yes)
				(filter_ratio 0.9)
				(enabled yes)
				(allow_two_segments yes)
				(prefer_zone_connections yes)
			)
		)
		(pad "B67" smd rect
			(at 5.75 3.325)
			(size 0.3 1.75)
			(layers "F.Cu" "F.Mask" "F.Paste")
			(net 388 "unconnected-(J12D-~{WAKE1}-PadB67)")
			(pinfunction "~{WAKE1}")
			(pintype "input+no_connect")
			(teardrops
				(best_length_ratio 0.2)
				(max_length 1)
				(best_width_ratio 0.9)
				(max_width 2)
				(curved_edges yes)
				(filter_ratio 0.9)
				(enabled yes)
				(allow_two_segments yes)
				(prefer_zone_connections yes)
			)
		)
		(pad "B68" smd rect
			(at 6.25 3.325)
			(size 0.3 1.75)
			(layers "F.Cu" "F.Mask" "F.Paste")
			(net 222 "/Com Express 7 Interfaces/PCIe_{B1x4}.RX0+")
			(pinfunction "PCIE_RX0+")
			(pintype "input")
			(teardrops
				(best_length_ratio 0.2)
				(max_length 1)
				(best_width_ratio 0.9)
				(max_width 2)
				(curved_edges yes)
				(filter_ratio 0.9)
				(enabled yes)
				(allow_two_segments yes)
				(prefer_zone_connections yes)
			)
		)
		(pad "B69" smd rect
			(at 6.75 3.325)
			(size 0.3 1.75)
			(layers "F.Cu" "F.Mask" "F.Paste")
			(net 221 "/Com Express 7 Interfaces/PCIe_{B1x4}.RX0-")
			(pinfunction "PCIE_RX0-")
			(pintype "input")
			(teardrops
				(best_length_ratio 0.2)
				(max_length 1)
				(best_width_ratio 0.9)
				(max_width 2)
				(curved_edges yes)
				(filter_ratio 0.9)
				(enabled yes)
				(allow_two_segments yes)
				(prefer_zone_connections yes)
			)
		)
		(pad "B70" smd rect
			(at 7.25 3.325)
			(size 0.3 1.75)
			(layers "F.Cu" "F.Mask" "F.Paste")
			(net 1 "GND")
			(pinfunction "GND(FIXED)")
			(pintype "passive")
			(teardrops
				(best_length_ratio 0.2)
				(max_length 1)
				(best_width_ratio 0.9)
				(max_width 2)
				(curved_edges yes)
				(filter_ratio 0.9)
				(enabled yes)
				(allow_two_segments yes)
				(prefer_zone_connections yes)
			)
		)
		(pad "B71" smd rect
			(at 7.75 3.325)
			(size 0.3 1.75)
			(layers "F.Cu" "F.Mask" "F.Paste")
			(net 90 "/Com Express 7 Interfaces/PCIe_{B2Ax4}.RX0+")
			(pinfunction "PCIE_RX8+")
			(pintype "input")
			(teardrops
				(best_length_ratio 0.2)
				(max_length 1)
				(best_width_ratio 0.9)
				(max_width 2)
				(curved_edges yes)
				(filter_ratio 0.9)
				(enabled yes)
				(allow_two_segments yes)
				(prefer_zone_connections yes)
			)
		)
		(pad "B72" smd rect
			(at 8.25 3.325)
			(size 0.3 1.75)
			(layers "F.Cu" "F.Mask" "F.Paste")
			(net 86 "/Com Express 7 Interfaces/PCIe_{B2Ax4}.RX0-")
			(pinfunction "PCIE_RX8-")
			(pintype "input")
			(teardrops
				(best_length_ratio 0.2)
				(max_length 1)
				(best_width_ratio 0.9)
				(max_width 2)
				(curved_edges yes)
				(filter_ratio 0.9)
				(enabled yes)
				(allow_two_segments yes)
				(prefer_zone_connections yes)
			)
		)
		(pad "B73" smd rect
			(at 8.75 3.325)
			(size 0.3 1.75)
			(layers "F.Cu" "F.Mask" "F.Paste")
			(net 1 "GND")
			(pinfunction "GND")
			(pintype "passive")
			(teardrops
				(best_length_ratio 0.2)
				(max_length 1)
				(best_width_ratio 0.9)
				(max_width 2)
				(curved_edges yes)
				(filter_ratio 0.9)
				(enabled yes)
				(allow_two_segments yes)
				(prefer_zone_connections yes)
			)
		)
		(pad "B74" smd rect
			(at 9.25 3.325)
			(size 0.3 1.75)
			(layers "F.Cu" "F.Mask" "F.Paste")
			(net 91 "/Com Express 7 Interfaces/PCIe_{B2Ax4}.RX1+")
			(pinfunction "PCIE_RX9+")
			(pintype "input")
			(teardrops
				(best_length_ratio 0.2)
				(max_length 1)
				(best_width_ratio 0.9)
				(max_width 2)
				(curved_edges yes)
				(filter_ratio 0.9)
				(enabled yes)
				(allow_two_segments yes)
				(prefer_zone_connections yes)
			)
		)
		(pad "B75" smd rect
			(at 9.75 3.325)
			(size 0.3 1.75)
			(layers "F.Cu" "F.Mask" "F.Paste")
			(net 87 "/Com Express 7 Interfaces/PCIe_{B2Ax4}.RX1-")
			(pinfunction "PCIE_RX9-")
			(pintype "input")
			(teardrops
				(best_length_ratio 0.2)
				(max_length 1)
				(best_width_ratio 0.9)
				(max_width 2)
				(curved_edges yes)
				(filter_ratio 0.9)
				(enabled yes)
				(allow_two_segments yes)
				(prefer_zone_connections yes)
			)
		)
		(pad "B76" smd rect
			(at 10.25 3.325)
			(size 0.3 1.75)
			(layers "F.Cu" "F.Mask" "F.Paste")
			(net 1 "GND")
			(pinfunction "GND")
			(pintype "passive")
			(teardrops
				(best_length_ratio 0.2)
				(max_length 1)
				(best_width_ratio 0.9)
				(max_width 2)
				(curved_edges yes)
				(filter_ratio 0.9)
				(enabled yes)
				(allow_two_segments yes)
				(prefer_zone_connections yes)
			)
		)
		(pad "B77" smd rect
			(at 10.75 3.325)
			(size 0.3 1.75)
			(layers "F.Cu" "F.Mask" "F.Paste")
			(net 92 "/Com Express 7 Interfaces/PCIe_{B2Ax4}.RX2+")
			(pinfunction "PCIE_RX10+")
			(pintype "input")
			(teardrops
				(best_length_ratio 0.2)
				(max_length 1)
				(best_width_ratio 0.9)
				(max_width 2)
				(curved_edges yes)
				(filter_ratio 0.9)
				(enabled yes)
				(allow_two_segments yes)
				(prefer_zone_connections yes)
			)
		)
		(pad "B78" smd rect
			(at 11.25 3.325)
			(size 0.3 1.75)
			(layers "F.Cu" "F.Mask" "F.Paste")
			(net 88 "/Com Express 7 Interfaces/PCIe_{B2Ax4}.RX2-")
			(pinfunction "PCIE_RX10-")
			(pintype "input")
			(teardrops
				(best_length_ratio 0.2)
				(max_length 1)
				(best_width_ratio 0.9)
				(max_width 2)
				(curved_edges yes)
				(filter_ratio 0.9)
				(enabled yes)
				(allow_two_segments yes)
				(prefer_zone_connections yes)
			)
		)
		(pad "B79" smd rect
			(at 11.75 3.325)
			(size 0.3 1.75)
			(layers "F.Cu" "F.Mask" "F.Paste")
			(net 1 "GND")
			(pinfunction "GND")
			(pintype "passive")
			(teardrops
				(best_length_ratio 0.2)
				(max_length 1)
				(best_width_ratio 0.9)
				(max_width 2)
				(curved_edges yes)
				(filter_ratio 0.9)
				(enabled yes)
				(allow_two_segments yes)
				(prefer_zone_connections yes)
			)
		)
		(pad "B80" smd rect
			(at 12.25 3.325)
			(size 0.3 1.75)
			(layers "F.Cu" "F.Mask" "F.Paste")
			(net 1 "GND")
			(pinfunction "GND(FIXED)")
			(pintype "passive")
			(teardrops
				(best_length_ratio 0.2)
				(max_length 1)
				(best_width_ratio 0.9)
				(max_width 2)
				(curved_edges yes)
				(filter_ratio 0.9)
				(enabled yes)
				(allow_two_segments yes)
				(prefer_zone_connections yes)
			)
		)
		(pad "B81" smd rect
			(at 12.75 3.325)
			(size 0.3 1.75)
			(layers "F.Cu" "F.Mask" "F.Paste")
			(net 93 "/Com Express 7 Interfaces/PCIe_{B2Ax4}.RX3+")
			(pinfunction "PCIE_RX11+")
			(pintype "input")
			(teardrops
				(best_length_ratio 0.2)
				(max_length 1)
				(best_width_ratio 0.9)
				(max_width 2)
				(curved_edges yes)
				(filter_ratio 0.9)
				(enabled yes)
				(allow_two_segments yes)
				(prefer_zone_connections yes)
			)
		)
		(pad "B82" smd rect
			(at 13.25 3.325)
			(size 0.3 1.75)
			(layers "F.Cu" "F.Mask" "F.Paste")
			(net 89 "/Com Express 7 Interfaces/PCIe_{B2Ax4}.RX3-")
			(pinfunction "PCIE_RX11-")
			(pintype "input")
			(teardrops
				(best_length_ratio 0.2)
				(max_length 1)
				(best_width_ratio 0.9)
				(max_width 2)
				(curved_edges yes)
				(filter_ratio 0.9)
				(enabled yes)
				(allow_two_segments yes)
				(prefer_zone_connections yes)
			)
		)
		(pad "B83" smd rect
			(at 13.75 3.325)
			(size 0.3 1.75)
			(layers "F.Cu" "F.Mask" "F.Paste")
			(net 1 "GND")
			(pinfunction "GND")
			(pintype "passive")
			(teardrops
				(best_length_ratio 0.2)
				(max_length 1)
				(best_width_ratio 0.9)
				(max_width 2)
				(curved_edges yes)
				(filter_ratio 0.9)
				(enabled yes)
				(allow_two_segments yes)
				(prefer_zone_connections yes)
			)
		)
		(pad "B84" smd rect
			(at 14.25 3.325)
			(size 0.3 1.75)
			(layers "F.Cu" "F.Mask" "F.Paste")
			(net 77 "+5V_AON")
			(pinfunction "VCC_5V_SBY")
			(pintype "power_in")
			(teardrops
				(best_length_ratio 0.2)
				(max_length 1)
				(best_width_ratio 0.9)
				(max_width 2)
				(curved_edges yes)
				(filter_ratio 0.9)
				(enabled yes)
				(allow_two_segments yes)
				(prefer_zone_connections yes)
			)
		)
		(pad "B85" smd rect
			(at 14.75 3.325)
			(size 0.3 1.75)
			(layers "F.Cu" "F.Mask" "F.Paste")
			(net 77 "+5V_AON")
			(pinfunction "VCC_5V_SBY")
			(pintype "passive")
			(teardrops
				(best_length_ratio 0.2)
				(max_length 1)
				(best_width_ratio 0.9)
				(max_width 2)
				(curved_edges yes)
				(filter_ratio 0.9)
				(enabled yes)
				(allow_two_segments yes)
				(prefer_zone_connections yes)
			)
		)
		(pad "B86" smd rect
			(at 15.25 3.325)
			(size 0.3 1.75)
			(layers "F.Cu" "F.Mask" "F.Paste")
			(net 77 "+5V_AON")
			(pinfunction "VCC_5V_SBY")
			(pintype "passive")
			(teardrops
				(best_length_ratio 0.2)
				(max_length 1)
				(best_width_ratio 0.9)
				(max_width 2)
				(curved_edges yes)
				(filter_ratio 0.9)
				(enabled yes)
				(allow_two_segments yes)
				(prefer_zone_connections yes)
			)
		)
		(pad "B87" smd rect
			(at 15.75 3.325)
			(size 0.3 1.75)
			(layers "F.Cu" "F.Mask" "F.Paste")
			(net 77 "+5V_AON")
			(pinfunction "VCC_5V_SBY")
			(pintype "passive")
			(teardrops
				(best_length_ratio 0.2)
				(max_length 1)
				(best_width_ratio 0.9)
				(max_width 2)
				(curved_edges yes)
				(filter_ratio 0.9)
				(enabled yes)
				(allow_two_segments yes)
				(prefer_zone_connections yes)
			)
		)
		(pad "B88" smd rect
			(at 16.25 3.325)
			(size 0.3 1.75)
			(layers "F.Cu" "F.Mask" "F.Paste")
			(net 389 "Net-(J12D-~{BIOS_DIS1})")
			(pinfunction "~{BIOS_DIS1}")
			(pintype "input")
			(teardrops
				(best_length_ratio 0.2)
				(max_length 1)
				(best_width_ratio 0.9)
				(max_width 2)
				(curved_edges yes)
				(filter_ratio 0.9)
				(enabled yes)
				(allow_two_segments yes)
				(prefer_zone_connections yes)
			)
		)
		(pad "B89" smd rect
			(at 16.75 3.325)
			(size 0.3 1.75)
			(layers "F.Cu" "F.Mask" "F.Paste")
			(net 390 "unconnected-(J12A-NCSI_RX_ER-PadB89)")
			(pinfunction "NCSI_RX_ER")
			(pintype "input+no_connect")
			(teardrops
				(best_length_ratio 0.2)
				(max_length 1)
				(best_width_ratio 0.9)
				(max_width 2)
				(curved_edges yes)
				(filter_ratio 0.9)
				(enabled yes)
				(allow_two_segments yes)
				(prefer_zone_connections yes)
			)
		)
	)
)
